# S9S_MB_2U (Grand Teton) — schematic netlist excerpt (pin names and nets, part order shuffled) for the footprints in the layout excerpt that follows; sources: Cadence DE-HDL packaged netlist, KiCad conversion of 03242023_DA0F0TMBIJ0_F0T_Motherboard_J_brd_V01_OCP.brd

R4734  Q_RES  0 5% CHIP  pkg 0402LF  page 227 : A = PRSNT_CABLE_GPU_B3_ISO_N ; B = PRSNT_CABLE_GPU_B3_ISO_R1_N
R3515  Q_RES  49.9 1% CHIP  pkg 0402LF  page 149 : A = FM_SWB_PWR_EN_R1_BUF ; B = FM_SWB_PWR_EN_R_BUF

(kicad_pcb
	(version 20260206)
	(generator "pcbnew")
	(generator_version "10.0")
	(general
		(thickness 1.6)
		(legacy_teardrops no)
	)
	(paper "A4")
	(title_block
		(title "03242023_DA0F0TMBIJ0_F0T_Motherboard_J_brd_V01_OCP.brd")
		(comment 1 "Grand Teton / footprints 3655-3656 of 6105")
	)
	(layers
		(0 "F.Cu" signal "TOP")
		(4 "In1.Cu" signal "GND")
		(6 "In2.Cu" signal "IN1")
		(8 "In3.Cu" signal "GND1")
		(10 "In4.Cu" signal "IN2")
		(12 "In5.Cu" signal "GND2")
		(14 "In6.Cu" signal "IN3")
		(16 "In7.Cu" signal "GND3")
		(18 "In8.Cu" signal "VCC")
		(20 "In9.Cu" signal "VCC1")
		(22 "In10.Cu" signal "GND4")
		(24 "In11.Cu" signal "IN4")
		(26 "In12.Cu" signal "GND5")
		(28 "In13.Cu" signal "IN5")
		(30 "In14.Cu" signal "GND6")
		(32 "In15.Cu" signal "IN6")
		(34 "In16.Cu" signal "GND7")
		(2 "B.Cu" signal "BOTTOM")
		(9 "F.Adhes" user "F.Adhesive")
		(11 "B.Adhes" user "B.Adhesive")
		(13 "F.Paste" user "Package Geometry/Pastemask Top")
		(15 "B.Paste" user "Package Geometry/Pastemask Bottom")
		(5 "F.SilkS" user "Ref Des/Silkscreen Top")
		(7 "B.SilkS" user "Ref Des/Silkscreen Bottom")
		(1 "F.Mask" user "Board Geometry/Soldermask Top")
		(3 "B.Mask" user "Board Geometry/Soldermask Bottom")
		(17 "Dwgs.User" user "User.Drawings")
		(19 "Cmts.User" user "User.Comments")
		(21 "Eco1.User" user "User.Eco1")
		(23 "Eco2.User" user "User.Eco2")
		(25 "Edge.Cuts" user "Board Geometry/Outline")
		(27 "Margin" user)
		(31 "F.CrtYd" user "Package Geometry/Place Bound Top")
		(29 "B.CrtYd" user "Package Geometry/Place Bound Bottom")
		(35 "F.Fab" user "Ref Des/Assembly Top")
		(33 "B.Fab" user "Ref Des/Assembly Bottom")
	)
	(footprint ""
		(layer "F.Cu")
		(at 31.29788 -431.891948)
		(property "Reference" "R3515"
			(at 0 0 0)
			(layer "F.SilkS")
			(hide yes)
			(effects
				(font
					(size 1.27 1.27)
				)
			)
		)
		(property "Value" ""
			(at 0 0 0)
			(layer "F.Fab")
			(effects
				(font
					(size 1.27 1.27)
				)
			)
		)
		(duplicate_pad_numbers_are_jumpers no)
		(fp_line
			(start -0.7874 -0.4064)
			(end 0.7874 -0.4064)
			(stroke
				(width 0.1524)
				(type default)
			)
			(layer "F.SilkS")
		)
		(fp_line
			(start -0.7874 0.4064)
			(end -0.7874 -0.4064)
			(stroke
				(width 0.1524)
				(type default)
			)
			(layer "F.SilkS")
		)
		(fp_line
			(start 0.7874 -0.4064)
			(end 0.7874 0.4064)
			(stroke
				(width 0.1524)
				(type default)
			)
			(layer "F.SilkS")
		)
		(fp_line
			(start 0.7874 0.4064)
			(end -0.7874 0.4064)
			(stroke
				(width 0.1524)
				(type default)
			)
			(layer "F.SilkS")
		)
		(fp_line
			(start -0.67945 -0.305054)
			(end -0.12065 -0.305054)
			(stroke
				(width 0.1)
				(type default)
			)
			(layer "F.Fab")
		)
		(fp_line
			(start -0.67945 0.3048)
			(end -0.67945 -0.305054)
			(stroke
				(width 0.1)
				(type default)
			)
			(layer "F.Fab")
		)
		(fp_line
			(start -0.12065 -0.305054)
			(end -0.12065 -0.2794)
			(stroke
				(width 0.1)
				(type default)
			)
			(layer "F.Fab")
		)
		(fp_line
			(start -0.12065 -0.2794)
			(end 0.12065 -0.2794)
			(stroke
				(width 0.1)
				(type default)
			)
			(layer "F.Fab")
		)
		(fp_line
			(start -0.12065 0.2794)
			(end -0.12065 0.3048)
			(stroke
				(width 0.1)
				(type default)
			)
			(layer "F.Fab")
		)
		(fp_line
			(start -0.12065 0.3048)
			(end -0.67945 0.3048)
			(stroke
				(width 0.1)
				(type default)
			)
			(layer "F.Fab")
		)
		(fp_line
			(start 0.120396 0.2794)
			(end -0.12065 0.2794)
			(stroke
				(width 0.1)
				(type default)
			)
			(layer "F.Fab")
		)
		(fp_line
			(start 0.120396 0.3048)
			(end 0.120396 0.2794)
			(stroke
				(width 0.1)
				(type default)
			)
			(layer "F.Fab")
		)
		(fp_line
			(start 0.12065 -0.3048)
			(end 0.67945 -0.3048)
			(stroke
				(width 0.1)
				(type default)
			)
			(layer "F.Fab")
		)
		(fp_line
			(start 0.12065 -0.2794)
			(end 0.12065 -0.3048)
			(stroke
				(width 0.1)
				(type default)
			)
			(layer "F.Fab")
		)
		(fp_line
			(start 0.67945 -0.3048)
			(end 0.67945 0.3048)
			(stroke
				(width 0.1)
				(type default)
			)
			(layer "F.Fab")
		)
		(fp_line
			(start 0.67945 0.3048)
			(end 0.120396 0.3048)
			(stroke
				(width 0.1)
				(type default)
			)
			(layer "F.Fab")
		)
		(pad "1" smd circle
			(at -0.40005 0)
			(size 0 0)
			(layers "F.Cu" "F.Mask" "F.Paste")
			(net "FM_SWB_PWR_EN_R1_BUF")
		)
		(pad "2" smd circle
			(at 0.40005 0)
			(size 0 0)
			(layers "F.Cu" "F.Mask" "F.Paste")
			(net "FM_SWB_PWR_EN_R_BUF")
		)
	)
	(footprint ""
		(layer "F.Cu")
		(at 20.8026 -410.7942 90)
		(property "Reference" "R4734"
			(at 0 0 90)
			(layer "F.SilkS")
			(hide yes)
			(effects
				(font
					(size 1.27 1.27)
				)
			)
		)
		(property "Value" ""
			(at 0 0 90)
			(layer "F.Fab")
			(effects
				(font
					(size 1.27 1.27)
				)
			)
		)
		(duplicate_pad_numbers_are_jumpers no)
		(fp_line
			(start 0.7874 -0.4064)
			(end 0.7874 0.4064)
			(stroke
				(width 0.1524)
				(type default)
			)
			(layer "F.SilkS")
		)
		(fp_line
			(start -0.7874 -0.4064)
			(end 0.7874 -0.4064)
			(stroke
				(width 0.1524)
				(type default)
			)
			(layer "F.SilkS")
		)
		(fp_line
			(start 0.7874 0.4064)
			(end -0.7874 0.4064)
			(stroke
				(width 0.1524)
				(type default)
			)
			(layer "F.SilkS")
		)
		(fp_line
			(start -0.7874 0.4064)
			(end -0.7874 -0.4064)
			(stroke
				(width 0.1524)
				(type default)
			)
			(layer "F.SilkS")
		)
		(fp_line
			(start -0.12065 -0.305054)
			(end -0.12065 -0.2794)
			(stroke
				(width 0.1)
				(type default)
			)
			(layer "F.Fab")
		)
		(fp_line
			(start -0.67945 -0.305054)
			(end -0.12065 -0.305054)
			(stroke
				(width 0.1)
				(type default)
			)
			(layer "F.Fab")
		)
		(fp_line
			(start 0.67945 -0.3048)
			(end 0.67945 0.3048)
			(stroke
				(width 0.1)
				(type default)
			)
			(layer "F.Fab")
		)
		(fp_line
			(start 0.12065 -0.3048)
			(end 0.67945 -0.3048)
			(stroke
				(width 0.1)
				(type default)
			)
			(layer "F.Fab")
		)
		(fp_line
			(start 0.12065 -0.2794)
			(end 0.12065 -0.3048)
			(stroke
				(width 0.1)
				(type default)
			)
			(layer "F.Fab")
		)
		(fp_line
			(start -0.12065 -0.2794)
			(end 0.12065 -0.2794)
			(stroke
				(width 0.1)
				(type default)
			)
			(layer "F.Fab")
		)
		(fp_line
			(start 0.120396 0.2794)
			(end -0.12065 0.2794)
			(stroke
				(width 0.1)
				(type default)
			)
			(layer "F.Fab")
		)
		(fp_line
			(start -0.12065 0.2794)
			(end -0.12065 0.3048)
			(stroke
				(width 0.1)
				(type default)
			)
			(layer "F.Fab")
		)
		(fp_line
			(start 0.67945 0.3048)
			(end 0.120396 0.3048)
			(stroke
				(width 0.1)
				(type default)
			)
			(layer "F.Fab")
		)
		(fp_line
			(start 0.120396 0.3048)
			(end 0.120396 0.2794)
			(stroke
				(width 0.1)
				(type default)
			)
			(layer "F.Fab")
		)
		(fp_line
			(start -0.12065 0.3048)
			(end -0.67945 0.3048)
			(stroke
				(width 0.1)
				(type default)
			)
			(layer "F.Fab")
		)
		(fp_line
			(start -0.67945 0.3048)
			(end -0.67945 -0.305054)
			(stroke
				(width 0.1)
				(type default)
			)
			(layer "F.Fab")
		)
		(pad "1" smd circle
			(at -0.40005 0 90)
			(size 0 0)
			(layers "F.Cu" "F.Mask" "F.Paste")
			(net "PRSNT_CABLE_GPU_B3_ISO_N")
		)
		(pad "2" smd circle
			(at 0.40005 0 90)
			(size 0 0)
			(layers "F.Cu" "F.Mask" "F.Paste")
			(net "PRSNT_CABLE_GPU_B3_ISO_R1_N")
		)
	)
)
